# T6G (Grand Teton) — schematic netlist excerpt (pin names and nets, part order shuffled) for the footprints in the layout excerpt that follows; sources: Cadence DE-HDL packaged netlist, KiCad conversion of 04192023_DAF0TMB3IC0_F0TG_MB_C_brd_V02_OCP.brd

PC78  Q_CAP  470PF 50V 10% X7R  pkg 0402  page 200 : A = PVDDCR_CPU1_P0_TEMP0 ; B = GND
D83  Q_LED  IC  pkg SMLF  page 256 : A = LED_PWRGD_PVDDIO_P1_R ; C = LED_PWRGD_PVDDIO_P1_D
C939  Q_CAP_DIFFBUS  DIFF BUS_0.22UF 6.3V 20% X6S  pkg C0201  page 63 : \1\ = P5E_CPU0_P1_TX_C_DP<13> ; \2\ = P5E_CPU0_P1_TX_DP<13>

(kicad_pcb
	(version 20260206)
	(generator "pcbnew")
	(generator_version "10.0")
	(general
		(thickness 1.6)
		(legacy_teardrops no)
	)
	(paper "A4")
	(title_block
		(title "04192023_DAF0TMB3IC0_F0TG_MB_C_brd_V02_OCP.brd")
		(comment 1 "Grand Teton / footprints 2792-2794 of 8354")
	)
	(layers
		(0 "F.Cu" signal "TOP")
		(4 "In1.Cu" signal "GND")
		(6 "In2.Cu" signal "IN1")
		(8 "In3.Cu" signal "GND1")
		(10 "In4.Cu" signal "IN2")
		(12 "In5.Cu" signal "GND2")
		(14 "In6.Cu" signal "IN3")
		(16 "In7.Cu" signal "GND3")
		(18 "In8.Cu" signal "VCC")
		(20 "In9.Cu" signal "VCC1")
		(22 "In10.Cu" signal "GND4")
		(24 "In11.Cu" signal "IN4")
		(26 "In12.Cu" signal "GND5")
		(28 "In13.Cu" signal "IN5")
		(30 "In14.Cu" signal "GND6")
		(32 "In15.Cu" signal "IN6")
		(34 "In16.Cu" signal "GND7")
		(2 "B.Cu" signal "BOTTOM")
		(9 "F.Adhes" user "F.Adhesive")
		(11 "B.Adhes" user "B.Adhesive")
		(13 "F.Paste" user "Package Geometry/Pastemask Top")
		(15 "B.Paste" user "Package Geometry/Pastemask Bottom")
		(5 "F.SilkS" user "Ref Des/Silkscreen Top")
		(7 "B.SilkS" user "Ref Des/Silkscreen Bottom")
		(1 "F.Mask" user "Board Geometry/Soldermask Top")
		(3 "B.Mask" user "Board Geometry/Soldermask Bottom")
		(17 "Dwgs.User" user "User.Drawings")
		(19 "Cmts.User" user "User.Comments")
		(21 "Eco1.User" user "User.Eco1")
		(23 "Eco2.User" user "User.Eco2")
		(25 "Edge.Cuts" user "Board Geometry/Outline")
		(27 "Margin" user)
		(31 "F.CrtYd" user "Package Geometry/Place Bound Top")
		(29 "B.CrtYd" user "Package Geometry/Place Bound Bottom")
		(35 "F.Fab" user "Ref Des/Assembly Top")
		(33 "B.Fab" user "Ref Des/Assembly Bottom")
	)
	(footprint ""
		(layer "F.Cu")
		(at 315.813186 -361.279948)
		(property "Reference" "PC78"
			(at 0 0 0)
			(layer "F.SilkS")
			(hide yes)
			(effects
				(font
					(size 1.27 1.27)
				)
			)
		)
		(property "Value" ""
			(at 0 0 0)
			(layer "F.Fab")
			(effects
				(font
					(size 1.27 1.27)
				)
			)
		)
		(duplicate_pad_numbers_are_jumpers no)
		(fp_line
			(start -0.7874 -0.4064)
			(end 0.7874 -0.4064)
			(stroke
				(width 0.1524)
				(type default)
			)
			(layer "F.SilkS")
		)
		(fp_line
			(start -0.7874 0.4064)
			(end -0.7874 -0.4064)
			(stroke
				(width 0.1524)
				(type default)
			)
			(layer "F.SilkS")
		)
		(fp_line
			(start 0.7874 -0.4064)
			(end 0.7874 0.4064)
			(stroke
				(width 0.1524)
				(type default)
			)
			(layer "F.SilkS")
		)
		(fp_line
			(start 0.7874 0.4064)
			(end -0.7874 0.4064)
			(stroke
				(width 0.1524)
				(type default)
			)
			(layer "F.SilkS")
		)
		(fp_line
			(start -0.67945 -0.305054)
			(end -0.12065 -0.305054)
			(stroke
				(width 0.1)
				(type default)
			)
			(layer "F.Fab")
		)
		(fp_line
			(start -0.67945 0.3048)
			(end -0.67945 -0.305054)
			(stroke
				(width 0.1)
				(type default)
			)
			(layer "F.Fab")
		)
		(fp_line
			(start -0.12065 -0.305054)
			(end -0.12065 -0.2794)
			(stroke
				(width 0.1)
				(type default)
			)
			(layer "F.Fab")
		)
		(fp_line
			(start -0.12065 -0.2794)
			(end 0.12065 -0.2794)
			(stroke
				(width 0.1)
				(type default)
			)
			(layer "F.Fab")
		)
		(fp_line
			(start -0.12065 0.2794)
			(end -0.12065 0.3048)
			(stroke
				(width 0.1)
				(type default)
			)
			(layer "F.Fab")
		)
		(fp_line
			(start -0.12065 0.3048)
			(end -0.67945 0.3048)
			(stroke
				(width 0.1)
				(type default)
			)
			(layer "F.Fab")
		)
		(fp_line
			(start 0.120396 0.2794)
			(end -0.12065 0.2794)
			(stroke
				(width 0.1)
				(type default)
			)
			(layer "F.Fab")
		)
		(fp_line
			(start 0.120396 0.3048)
			(end 0.120396 0.2794)
			(stroke
				(width 0.1)
				(type default)
			)
			(layer "F.Fab")
		)
		(fp_line
			(start 0.12065 -0.3048)
			(end 0.67945 -0.3048)
			(stroke
				(width 0.1)
				(type default)
			)
			(layer "F.Fab")
		)
		(fp_line
			(start 0.12065 -0.2794)
			(end 0.12065 -0.3048)
			(stroke
				(width 0.1)
				(type default)
			)
			(layer "F.Fab")
		)
		(fp_line
			(start 0.67945 -0.3048)
			(end 0.67945 0.3048)
			(stroke
				(width 0.1)
				(type default)
			)
			(layer "F.Fab")
		)
		(fp_line
			(start 0.67945 0.3048)
			(end 0.120396 0.3048)
			(stroke
				(width 0.1)
				(type default)
			)
			(layer "F.Fab")
		)
		(pad "1" smd circle
			(at -0.40005 0)
			(size 0 0)
			(layers "F.Cu" "F.Mask" "F.Paste")
			(net "PVDDCR_CPU1_P0_TEMP0")
		)
		(pad "2" smd circle
			(at 0.40005 0)
			(size 0 0)
			(layers "F.Cu" "F.Mask" "F.Paste")
			(net "GND")
		)
	)
	(footprint ""
		(layer "F.Cu")
		(at 357.044244 -378.95403 -90)
		(property "Reference" "C939"
			(at 0 0 270)
			(layer "F.SilkS")
			(hide yes)
			(effects
				(font
					(size 1.27 1.27)
				)
			)
		)
		(property "Value" ""
			(at 0 0 270)
			(layer "F.Fab")
			(effects
				(font
					(size 1.27 1.27)
				)
			)
		)
		(duplicate_pad_numbers_are_jumpers no)
		(fp_line
			(start -0.299974 0.150114)
			(end -0.299974 -0.150114)
			(stroke
				(width 0.1)
				(type default)
			)
			(layer "F.Fab")
		)
		(fp_line
			(start 0.299974 0.150114)
			(end -0.299974 0.150114)
			(stroke
				(width 0.1)
				(type default)
			)
			(layer "F.Fab")
		)
		(fp_line
			(start -0.299974 -0.150114)
			(end 0.299974 -0.150114)
			(stroke
				(width 0.1)
				(type default)
			)
			(layer "F.Fab")
		)
		(fp_line
			(start 0.299974 -0.150114)
			(end 0.299974 0.150114)
			(stroke
				(width 0.1)
				(type default)
			)
			(layer "F.Fab")
		)
		(pad "1" smd rect
			(at -0.2667 0 270)
			(size 0.3048 0.381)
			(layers "F.Cu" "F.Mask" "F.Paste")
			(net "P5E_CPU0_P1_TX_C_DP<13>")
		)
		(pad "2" smd rect
			(at 0.2667 0 270)
			(size 0.3048 0.381)
			(layers "F.Cu" "F.Mask" "F.Paste")
			(net "P5E_CPU0_P1_TX_DP<13>")
		)
	)
	(footprint ""
		(layer "F.Cu")
		(at 342.923876 -70.098412 90)
		(property "Reference" "D83"
			(at -3.934714 -0.691642 90)
			(unlocked yes)
			(layer "F.SilkS")
			(effects
				(font
					(size 0.7874 0.5842)
					(thickness 0.1524)
				)
				(justify left)
			)
		)
		(property "Value" ""
			(at 0 0 90)
			(layer "F.Fab")
			(effects
				(font
					(size 1.27 1.27)
				)
			)
		)
		(duplicate_pad_numbers_are_jumpers no)
		(fp_line
			(start 1.16078 -0.4826)
			(end 1.16078 0.4826)
			(stroke
				(width 0.1524)
				(type default)
			)
			(layer "F.SilkS")
		)
		(fp_line
			(start 1.03378 -0.4826)
			(end 1.03378 0.4826)
			(stroke
				(width 0.1524)
				(type default)
			)
			(layer "F.SilkS")
		)
		(fp_line
			(start 0.90678 -0.4826)
			(end 0.90678 0.4826)
			(stroke
				(width 0.1524)
				(type default)
			)
			(layer "F.SilkS")
		)
		(fp_line
			(start -0.64008 -0.4826)
			(end 1.16078 -0.4826)
			(stroke
				(width 0.1524)
				(type default)
			)
			(layer "F.SilkS")
		)
		(fp_line
			(start -0.79248 -0.4826)
			(end 1.03378 -0.4826)
			(stroke
				(width 0.1524)
				(type default)
			)
			(layer "F.SilkS")
		)
		(fp_line
			(start -0.89408 -0.4826)
			(end 0.90678 -0.4826)
			(stroke
				(width 0.1524)
				(type default)
			)
			(layer "F.SilkS")
		)
		(fp_line
			(start 1.16078 0.4826)
			(end -0.64008 0.4826)
			(stroke
				(width 0.1524)
				(type default)
			)
			(layer "F.SilkS")
		)
		(fp_line
			(start 1.03378 0.4826)
			(end -0.79248 0.4826)
			(stroke
				(width 0.1524)
				(type default)
			)
			(layer "F.SilkS")
		)
		(fp_line
			(start 0.90678 0.4826)
			(end -0.90678 0.4826)
			(stroke
				(width 0.1524)
				(type default)
			)
			(layer "F.SilkS")
		)
		(fp_line
			(start -0.90678 0.4826)
			(end -0.90678 -0.4699)
			(stroke
				(width 0.1524)
				(type default)
			)
			(layer "F.SilkS")
		)
		(fp_line
			(start 0.499872 -0.249936)
			(end 0.499872 0.249936)
			(stroke
				(width 0.1)
				(type default)
			)
			(layer "F.Fab")
		)
		(fp_line
			(start -0.499872 -0.249936)
			(end 0.499872 -0.249936)
			(stroke
				(width 0.1)
				(type default)
			)
			(layer "F.Fab")
		)
		(fp_line
			(start 0.499872 0.249936)
			(end -0.499872 0.249936)
			(stroke
				(width 0.1)
				(type default)
			)
			(layer "F.Fab")
		)
		(fp_line
			(start -0.499872 0.249936)
			(end -0.499872 -0.249936)
			(stroke
				(width 0.1)
				(type default)
			)
			(layer "F.Fab")
		)
		(pad "A" smd rect
			(at -0.47498 0 90)
			(size 0.6096 0.7112)
			(layers "F.Cu" "F.Mask" "F.Paste")
			(net "LED_PWRGD_PVDDIO_P1_R")
		)
		(pad "C" smd rect
			(at 0.47498 0 90)
			(size 0.6096 0.7112)
			(layers "F.Cu" "F.Mask" "F.Paste")
			(net "LED_PWRGD_PVDDIO_P1_D")
		)
	)
)
